# T6G (Grand Teton) — schematic netlist excerpt (pin names and nets, part order shuffled) for the footprints in the layout excerpt that follows; sources: Cadence DE-HDL packaged netlist, KiCad conversion of 04192023_DAF0TMB3IC0_F0TG_MB_C_brd_V02_OCP.brd

C298  Q_CAP  10PF 50V 5% EMPTY  pkg 0402  page 193 : A = SVID_PVDDCR_CPU0_P0_SVTO ; B = GND

Y4  Q_XTAL_4P_13BI_24GND  48MHZ MISC  pkg X_4S_FL4000120_3-2X2-5  page 55
  X1  = XTAL_CPU1_X48M_X1
  G1  = GND
  X2  = XTAL_CPU1_X48M_X2_R
  G2  = GND

(kicad_pcb
	(version 20260206)
	(generator "pcbnew")
	(generator_version "10.0")
	(general
		(thickness 1.6)
		(legacy_teardrops no)
	)
	(paper "A4")
	(title_block
		(title "04192023_DAF0TMB3IC0_F0TG_MB_C_brd_V02_OCP.brd")
		(comment 1 "Grand Teton / footprints 7900-7901 of 8354")
	)
	(layers
		(0 "F.Cu" signal "TOP")
		(4 "In1.Cu" signal "GND")
		(6 "In2.Cu" signal "IN1")
		(8 "In3.Cu" signal "GND1")
		(10 "In4.Cu" signal "IN2")
		(12 "In5.Cu" signal "GND2")
		(14 "In6.Cu" signal "IN3")
		(16 "In7.Cu" signal "GND3")
		(18 "In8.Cu" signal "VCC")
		(20 "In9.Cu" signal "VCC1")
		(22 "In10.Cu" signal "GND4")
		(24 "In11.Cu" signal "IN4")
		(26 "In12.Cu" signal "GND5")
		(28 "In13.Cu" signal "IN5")
		(30 "In14.Cu" signal "GND6")
		(32 "In15.Cu" signal "IN6")
		(34 "In16.Cu" signal "GND7")
		(2 "B.Cu" signal "BOTTOM")
		(9 "F.Adhes" user "F.Adhesive")
		(11 "B.Adhes" user "B.Adhesive")
		(13 "F.Paste" user "Package Geometry/Pastemask Top")
		(15 "B.Paste" user "Package Geometry/Pastemask Bottom")
		(5 "F.SilkS" user "Ref Des/Silkscreen Top")
		(7 "B.SilkS" user "Ref Des/Silkscreen Bottom")
		(1 "F.Mask" user "Board Geometry/Soldermask Top")
		(3 "B.Mask" user "Board Geometry/Soldermask Bottom")
		(17 "Dwgs.User" user "User.Drawings")
		(19 "Cmts.User" user "User.Comments")
		(21 "Eco1.User" user "User.Eco1")
		(23 "Eco2.User" user "User.Eco2")
		(25 "Edge.Cuts" user "Board Geometry/Outline")
		(27 "Margin" user)
		(31 "F.CrtYd" user "Package Geometry/Place Bound Top")
		(29 "B.CrtYd" user "Package Geometry/Place Bound Bottom")
		(35 "F.Fab" user "Ref Des/Assembly Top")
		(33 "B.Fab" user "Ref Des/Assembly Bottom")
	)
	(footprint ""
		(layer "B.Cu")
		(at 149.087586 -316.88405 90)
		(property "Reference" "Y4"
			(at 2.626106 1.482598 0)
			(unlocked yes)
			(layer "B.SilkS")
			(effects
				(font
					(size 0.7874 0.5842)
					(thickness 0.1524)
				)
				(justify left mirror)
			)
		)
		(property "Value" ""
			(at 0 0 90)
			(layer "B.Fab")
			(effects
				(font
					(size 1.27 1.27)
				)
				(justify mirror)
			)
		)
		(duplicate_pad_numbers_are_jumpers no)
		(fp_line
			(start 1.538732 -1.937004)
			(end -1.538732 -1.937004)
			(stroke
				(width 0.1524)
				(type default)
			)
			(layer "B.SilkS")
		)
		(fp_line
			(start -1.538732 -1.937004)
			(end -1.538732 1.937004)
			(stroke
				(width 0.1524)
				(type default)
			)
			(layer "B.SilkS")
		)
		(fp_line
			(start 1.538732 1.937004)
			(end 1.538732 -1.937004)
			(stroke
				(width 0.1524)
				(type default)
			)
			(layer "B.SilkS")
		)
		(fp_line
			(start -1.538732 1.937004)
			(end 1.538732 1.937004)
			(stroke
				(width 0.1524)
				(type default)
			)
			(layer "B.SilkS")
		)
		(fp_poly
			(pts
				(xy 2.251964 -1.24841) (xy 3.118358 -1.681734) (xy 3.118358 -0.81534)
			)
			(stroke
				(width 0)
				(type default)
			)
			(fill yes)
			(layer "B.SilkS")
		)
		(fp_line
			(start 1.299972 -1.649984)
			(end -1.299972 -1.649984)
			(stroke
				(width 0.1)
				(type default)
			)
			(layer "B.Fab")
		)
		(fp_line
			(start -1.299972 -1.649984)
			(end -1.299972 1.649984)
			(stroke
				(width 0.1)
				(type default)
			)
			(layer "B.Fab")
		)
		(fp_line
			(start 1.299972 1.649984)
			(end 1.299972 -1.649984)
			(stroke
				(width 0.1)
				(type default)
			)
			(layer "B.Fab")
		)
		(fp_line
			(start -1.299972 1.649984)
			(end 1.299972 1.649984)
			(stroke
				(width 0.1)
				(type default)
			)
			(layer "B.Fab")
		)
		(fp_poly
			(pts
				(xy 2.5908 -0.626872) (xy 2.5908 -1.493266) (xy 1.724406 -1.059942)
			)
			(stroke
				(width 0)
				(type default)
			)
			(fill yes)
			(layer "B.Fab")
		)
		(pad "1" smd rect
			(at 0.8001 -1.059942 270)
			(size 1.2192 1.4986)
			(layers "B.Cu" "B.Mask" "B.Paste")
			(net "XTAL_CPU1_X48M_X1")
		)
		(pad "2" smd rect
			(at 0.8001 1.059942 270)
			(size 1.2192 1.4986)
			(layers "B.Cu" "B.Mask" "B.Paste")
			(net "GND")
		)
		(pad "3" smd rect
			(at -0.8001 1.059942 270)
			(size 1.2192 1.4986)
			(layers "B.Cu" "B.Mask" "B.Paste")
			(net "XTAL_CPU1_X48M_X2_R")
		)
		(pad "4" smd rect
			(at -0.8001 -1.059942 270)
			(size 1.2192 1.4986)
			(layers "B.Cu" "B.Mask" "B.Paste")
			(net "GND")
		)
	)
	(footprint ""
		(layer "B.Cu")
		(at 370.905278 -146.552158)
		(property "Reference" "C298"
			(at 0 0 0)
			(layer "B.SilkS")
			(hide yes)
			(effects
				(font
					(size 1.27 1.27)
				)
				(justify mirror)
			)
		)
		(property "Value" ""
			(at 0 0 0)
			(layer "B.Fab")
			(effects
				(font
					(size 1.27 1.27)
				)
				(justify mirror)
			)
		)
		(duplicate_pad_numbers_are_jumpers no)
		(fp_line
			(start -0.7874 -0.4064)
			(end -0.7874 0.4064)
			(stroke
				(width 0.1524)
				(type default)
			)
			(layer "B.SilkS")
		)
		(fp_line
			(start -0.7874 0.4064)
			(end 0.7874 0.4064)
			(stroke
				(width 0.1524)
				(type default)
			)
			(layer "B.SilkS")
		)
		(fp_line
			(start 0.7874 -0.4064)
			(end -0.7874 -0.4064)
			(stroke
				(width 0.1524)
				(type default)
			)
			(layer "B.SilkS")
		)
		(fp_line
			(start 0.7874 0.4064)
			(end 0.7874 -0.4064)
			(stroke
				(width 0.1524)
				(type default)
			)
			(layer "B.SilkS")
		)
		(fp_line
			(start -0.67945 -0.3048)
			(end -0.67945 0.3048)
			(stroke
				(width 0.1)
				(type default)
			)
			(layer "B.Fab")
		)
		(fp_line
			(start -0.67945 0.3048)
			(end -0.120396 0.3048)
			(stroke
				(width 0.1)
				(type default)
			)
			(layer "B.Fab")
		)
		(fp_line
			(start -0.12065 -0.3048)
			(end -0.67945 -0.3048)
			(stroke
				(width 0.1)
				(type default)
			)
			(layer "B.Fab")
		)
		(fp_line
			(start -0.12065 -0.2794)
			(end -0.12065 -0.3048)
			(stroke
				(width 0.1)
				(type default)
			)
			(layer "B.Fab")
		)
		(fp_line
			(start -0.120396 0.2794)
			(end 0.12065 0.2794)
			(stroke
				(width 0.1)
				(type default)
			)
			(layer "B.Fab")
		)
		(fp_line
			(start -0.120396 0.3048)
			(end -0.120396 0.2794)
			(stroke
				(width 0.1)
				(type default)
			)
			(layer "B.Fab")
		)
		(fp_line
			(start 0.12065 -0.305054)
			(end 0.12065 -0.2794)
			(stroke
				(width 0.1)
				(type default)
			)
			(layer "B.Fab")
		)
		(fp_line
			(start 0.12065 -0.2794)
			(end -0.12065 -0.2794)
			(stroke
				(width 0.1)
				(type default)
			)
			(layer "B.Fab")
		)
		(fp_line
			(start 0.12065 0.2794)
			(end 0.12065 0.3048)
			(stroke
				(width 0.1)
				(type default)
			)
			(layer "B.Fab")
		)
		(fp_line
			(start 0.12065 0.3048)
			(end 0.67945 0.3048)
			(stroke
				(width 0.1)
				(type default)
			)
			(layer "B.Fab")
		)
		(fp_line
			(start 0.67945 -0.305054)
			(end 0.12065 -0.305054)
			(stroke
				(width 0.1)
				(type default)
			)
			(layer "B.Fab")
		)
		(fp_line
			(start 0.67945 0.3048)
			(end 0.67945 -0.305054)
			(stroke
				(width 0.1)
				(type default)
			)
			(layer "B.Fab")
		)
		(pad "1" smd circle
			(at 0.40005 0 180)
			(size 0 0)
			(layers "B.Cu" "B.Mask" "B.Paste")
			(net "SVID_PVDDCR_CPU0_P0_SVTO")
		)
		(pad "2" smd circle
			(at -0.40005 0 180)
			(size 0 0)
			(layers "B.Cu" "B.Mask" "B.Paste")
			(net "GND")
		)
	)
)
